G04 ================== begin FILE IDENTIFICATION RECORD ==================*
G04 Layout Name:  12433-2a.brd*
G04 Film Name:    GOLD_T*
G04 File Format:  Gerber RS274X*
G04 File Origin:  Cadence Allegro 16.5-S056*
G04 Origin Date:  Fri Dec 11 16:47:39 2015*
G04 *
G04 Layer:  PACKAGE GEOMETRY/GOLDEN_TOP*
G04 Layer:  DRAWING FORMAT/LAYER_GOLD_T*
G04 Layer:  DRAWING FORMAT/LAYER_PCB_STORY*
G04 Layer:  BOARD GEOMETRY/GOLDEN_TOP*
G04 Layer:  BOARD GEOMETRY/PANEL_OUTLINE*
G04 *
G04 Offset:    (0.00 0.00)*
G04 Mirror:    No*
G04 Mode:      Positive*
G04 Rotation:  0*
G04 FullContactRelief:  No*
G04 UndefLineWidth:     6.00*
G04 ================== end FILE IDENTIFICATION RECORD ====================*
%FSLAX35Y35*MOIN*%
%IR0*IPPOS*OFA0.00000B0.00000*MIA0B0*SFA1.00000B1.00000*%
%ADD10C,.02*%
%ADD11C,.006*%
G75*
%LPD*%
G75*
G36*
G01X123426Y1772126D02*
Y1689960D01*
X69488D01*
Y1856890D01*
X123426D01*
Y1785512D01*
X119095D01*
G03Y1772126I0J-6693D01*
G01X123426D01*
G37*
G36*
G01X134448D02*
Y1689960D01*
X188386D01*
Y1856890D01*
X134448D01*
Y1785512D01*
X138779D01*
G02Y1772126I0J-6693D01*
G01X134448D01*
G37*
G54D10*
G01X-448201Y-66763D02*
X-480201D01*
G01X-448201Y-82763D02*
Y-162763D01*
G01Y-118263D02*
X752899D01*
G01X-448201Y-162763D02*
X752899D01*
G01X-452201Y-66763D02*
G02I-12000J0D01*
G01X-457351D02*
G02I-6850J0D01*
G01X-464201Y-82763D02*
Y-50763D01*
G01X-448201Y-82763D02*
X752899D01*
G01X-34601D02*
Y-162763D01*
G01X102899Y-82763D02*
Y-162763D01*
G01X217899Y-82763D02*
Y-162763D01*
G01X385399Y-82763D02*
Y-162763D01*
G01X555399Y-82763D02*
Y-162763D01*
G01X752899Y-82763D02*
Y-162763D01*
G01X780899Y-66763D02*
G02I-12000J0D01*
G01X775749D02*
G02I-6850J0D01*
G01X768899Y-82763D02*
Y-50763D01*
G01X784899Y-66763D02*
X752899D01*
G54D11*
G01X-430254Y-152763D02*
Y-135263D01*
G01X-421958D02*
X-430254Y-146055D01*
G01X-420648Y-152763D02*
X-426543Y-141097D01*
G01X-412973Y-152763D02*
Y-135263D01*
X-402929Y-152763D01*
Y-135263D01*
G01X-390451Y-152763D02*
X-392198Y-152471D01*
X-393726Y-151305D01*
X-395036Y-149555D01*
X-395910Y-147513D01*
X-396346Y-145180D01*
Y-142846D01*
X-395910Y-140513D01*
X-395036Y-138471D01*
X-393726Y-136722D01*
X-392198Y-135555D01*
X-390451Y-135263D01*
X-388705Y-135555D01*
X-387176Y-136722D01*
X-385866Y-138471D01*
X-384992Y-140513D01*
X-384556Y-142846D01*
Y-145180D01*
X-384992Y-147513D01*
X-385866Y-149555D01*
X-387176Y-151305D01*
X-388705Y-152471D01*
X-390451Y-152763D01*
G01X-377536D02*
X-368366Y-135263D01*
G01X-377536D02*
X-368366Y-152763D01*
G01X-362001Y-158596D02*
X-348901D01*
G01X-342099Y-152763D02*
Y-135263D01*
X-333803D01*
G01X-336859Y-143721D02*
X-342099D01*
G01X-325910Y-152763D02*
X-320451Y-135263D01*
X-314992Y-152763D01*
G01X-316958Y-146638D02*
X-323945D01*
G01X-307973Y-152763D02*
Y-135263D01*
X-297929Y-152763D01*
Y-135263D01*
G01X-263148Y-136722D02*
X-264458Y-135846D01*
X-265986Y-135263D01*
X-267733D01*
X-269698Y-136138D01*
X-271226Y-137596D01*
X-272318Y-139347D01*
X-273191Y-142263D01*
X-273410Y-144888D01*
X-272973Y-147513D01*
X-272318Y-149263D01*
X-271008Y-151013D01*
X-269479Y-152180D01*
X-267951Y-152763D01*
X-266423D01*
X-264894Y-152180D01*
X-263584Y-151305D01*
X-262492Y-150139D01*
G01X-250451Y-152763D02*
X-252198Y-152471D01*
X-253726Y-151305D01*
X-255036Y-149555D01*
X-255910Y-147513D01*
X-256346Y-145180D01*
Y-142846D01*
X-255910Y-140513D01*
X-255036Y-138471D01*
X-253726Y-136722D01*
X-252198Y-135555D01*
X-250451Y-135263D01*
X-248705Y-135555D01*
X-247176Y-136722D01*
X-245866Y-138471D01*
X-244992Y-140513D01*
X-244556Y-142846D01*
Y-145180D01*
X-244992Y-147513D01*
X-245866Y-149555D01*
X-247176Y-151305D01*
X-248705Y-152471D01*
X-250451Y-152763D01*
G01X-237973D02*
Y-135263D01*
X-227929Y-152763D01*
Y-135263D01*
G01X-215451D02*
Y-152763D01*
G01X-220473Y-135263D02*
X-210429D01*
G01X-202318Y-152763D02*
Y-135263D01*
X-196859D01*
X-195113Y-136138D01*
X-194021Y-137305D01*
X-193584Y-139638D01*
X-194021Y-141972D01*
X-195331Y-143430D01*
X-196859Y-144305D01*
X-202318D01*
G01X-196859D02*
X-193584Y-152763D01*
G01X-180451D02*
X-182198Y-152471D01*
X-183726Y-151305D01*
X-185036Y-149555D01*
X-185910Y-147513D01*
X-186346Y-145180D01*
Y-142846D01*
X-185910Y-140513D01*
X-185036Y-138471D01*
X-183726Y-136722D01*
X-182198Y-135555D01*
X-180451Y-135263D01*
X-178705Y-135555D01*
X-177176Y-136722D01*
X-175866Y-138471D01*
X-174992Y-140513D01*
X-174556Y-142846D01*
Y-145180D01*
X-174992Y-147513D01*
X-175866Y-149555D01*
X-177176Y-151305D01*
X-178705Y-152471D01*
X-180451Y-152763D01*
G01X-167318Y-135263D02*
Y-152763D01*
X-158584D01*
G01X-126205Y-143430D02*
X-125331Y-142555D01*
X-124676Y-141097D01*
X-124239Y-139054D01*
X-124676Y-137305D01*
X-125549Y-136138D01*
X-127078Y-135263D01*
X-132973D01*
Y-152763D01*
X-125768D01*
X-124239Y-151597D01*
X-123366Y-149846D01*
X-122929Y-147805D01*
X-123366Y-145763D01*
X-124676Y-144013D01*
X-126205Y-143430D01*
X-132973D01*
G01X-110451Y-152763D02*
X-112198Y-152471D01*
X-113726Y-151305D01*
X-115036Y-149555D01*
X-115910Y-147513D01*
X-116346Y-145180D01*
Y-142846D01*
X-115910Y-140513D01*
X-115036Y-138471D01*
X-113726Y-136722D01*
X-112198Y-135555D01*
X-110451Y-135263D01*
X-108705Y-135555D01*
X-107176Y-136722D01*
X-105866Y-138471D01*
X-104992Y-140513D01*
X-104556Y-142846D01*
Y-145180D01*
X-104992Y-147513D01*
X-105866Y-149555D01*
X-107176Y-151305D01*
X-108705Y-152471D01*
X-110451Y-152763D01*
G01X-98410D02*
X-92951Y-135263D01*
X-87492Y-152763D01*
G01X-89458Y-146638D02*
X-96445D01*
G01X-79818Y-152763D02*
Y-135263D01*
X-74359D01*
X-72613Y-136138D01*
X-71521Y-137305D01*
X-71084Y-139638D01*
X-71521Y-141972D01*
X-72831Y-143430D01*
X-74359Y-144305D01*
X-79818D01*
G01X-74359D02*
X-71084Y-152763D01*
G01X-62754D02*
Y-135263D01*
X-58388D01*
X-56641Y-136138D01*
X-55331Y-137305D01*
X-54239Y-139054D01*
X-53366Y-141097D01*
X-53148Y-144013D01*
X-53366Y-146930D01*
X-54239Y-148972D01*
X-55331Y-150722D01*
X-56641Y-151888D01*
X-58388Y-152763D01*
X-62754D01*
G01X-282378Y-107763D02*
Y-90263D01*
X-276701Y-104846D01*
X-271024Y-90263D01*
Y-107763D01*
G01X-259201D02*
X-260511Y-107471D01*
X-261821Y-106305D01*
X-262695Y-104263D01*
X-263131Y-101930D01*
X-262695Y-99596D01*
X-261821Y-97555D01*
X-260511Y-96388D01*
X-259201Y-96097D01*
X-257891Y-96388D01*
X-256581Y-97555D01*
X-255708Y-99596D01*
X-255489Y-101930D01*
X-255708Y-104263D01*
X-256581Y-106305D01*
X-257891Y-107471D01*
X-259201Y-107763D01*
G01X-237771Y-90263D02*
Y-107763D01*
G01Y-105139D02*
X-238644Y-106597D01*
X-239955Y-107471D01*
X-241483Y-107763D01*
X-243229Y-107180D01*
X-244539Y-105722D01*
X-245413Y-103972D01*
X-245631Y-101930D01*
X-245413Y-99888D01*
X-244539Y-98138D01*
X-243229Y-96680D01*
X-241483Y-96097D01*
X-239955Y-96388D01*
X-238863Y-96972D01*
X-237771Y-98138D01*
G01X-227476Y-99888D02*
X-220489D01*
X-221144Y-97846D01*
X-222236Y-96680D01*
X-223764Y-96097D01*
X-225293Y-96388D01*
X-226603Y-97263D01*
X-227476Y-99305D01*
X-227913Y-101055D01*
Y-102805D01*
X-227476Y-104555D01*
X-226384Y-106305D01*
X-225074Y-107471D01*
X-223546Y-107763D01*
X-222018Y-107180D01*
X-220489Y-105430D01*
G01X-206701Y-107763D02*
Y-90263D01*
G01X-222441Y169326D02*
Y39370D01*
G01D02*
G03X-214567Y31496I7874J0D01*
G01X-242126Y15000D02*
G03X-227126Y0I15000J0D01*
G01X-242126Y1953504D02*
Y15000D01*
G01X-215453Y19685D02*
G03I-6988J0D01*
G01X-84646Y0D02*
X-227126D01*
G01X-215453Y19685D02*
G03I-6988J0D01*
G01D02*
G03I-6988J0D01*
G01X-214567Y169326D02*
G03X-222441I-3937J0D01*
G01X-214567D02*
G03X-222441I-3937J0D01*
G01Y436255D02*
Y200034D01*
G01D02*
G03X-214567I3937J0D01*
G01X-222441D02*
G03X-214567I3937J0D01*
G01Y436255D02*
G03X-222441I-3937J0D01*
G01X-214567D02*
G03X-222441I-3937J0D01*
G01Y703184D02*
Y466963D01*
G01D02*
G03X-214567I3937J0D01*
G01X-222441D02*
G03X-214567I3937J0D01*
G01Y703184D02*
G03X-222441I-3937J0D01*
G01X-214567D02*
G03X-222441I-3937J0D01*
G01Y970901D02*
Y733892D01*
G01D02*
G03X-214567I3937J0D01*
G01X-222441D02*
G03X-214567I3937J0D01*
G01X-222441Y1234681D02*
Y997672D01*
G01X-214567Y970901D02*
G03X-222441I-3937J0D01*
G01Y997672D02*
G03X-214567I3937J0D01*
G01Y970901D02*
G03X-222441I-3937J0D01*
G01Y997672D02*
G03X-214567I3937J0D01*
G01X-222441Y1501610D02*
Y1265389D01*
G01D02*
G03X-214567I3937J0D01*
G01Y1234681D02*
G03X-222441I-3937J0D01*
G01Y1265389D02*
G03X-214567I3937J0D01*
G01Y1234681D02*
G03X-222441I-3937J0D01*
G01X-214567Y1501610D02*
G03X-222441I-3937J0D01*
G01X-214567D02*
G03X-222441I-3937J0D01*
G01Y1768539D02*
Y1532318D01*
G01D02*
G03X-214567I3937J0D01*
G01X-222441D02*
G03X-214567I3937J0D01*
G01Y1768539D02*
G03X-222441I-3937J0D01*
G01X-214567D02*
G03X-222441I-3937J0D01*
G01Y1799247D02*
G03X-214567I3937J0D01*
G01X-222441D02*
G03X-214567I3937J0D01*
G01X-222441Y1929134D02*
Y1799247D01*
G01X-214567Y1937008D02*
G03X-222441Y1929134I0J-7874D01*
G01X-227126Y1968504D02*
G03X-242126Y1953504I0J-15000D01*
G01X-215453Y1948819D02*
G03I-6988J0D01*
G01X-84638Y1968504D02*
X-227126D01*
G01X-215453Y1948819D02*
G03I-6988J0D01*
G01D02*
G03I-6988J0D01*
G01X-214567Y43307D02*
G03X-210630Y39370I3937J0D01*
G01X-214567Y43307D02*
G03X-210630Y39370I3937J0D01*
G01X-80709D02*
X-210630D01*
G01X-80709D02*
X-210630D01*
G01X-206693Y31496D02*
X-214567D01*
G01X-175984D02*
X-84646D01*
G01X-206693D02*
G03Y39370I0J3937D01*
G01X-175984D02*
G03Y31496I0J-3937D01*
G01X-206693D02*
X-214567D01*
G01X-84646Y0D02*
X-199567D01*
G01X-175984Y31496D02*
X-84646D01*
G01X-206693D02*
G03Y39370I0J3937D01*
G01X-175984D02*
G03Y31496I0J-3937D01*
G01X-214567Y43307D02*
Y1925197D01*
G01Y43307D02*
Y1925197D01*
G01Y149606D02*
Y43307D01*
G01Y149606D02*
Y43272D01*
G01Y1807087D02*
Y161417D01*
G01Y1807087D02*
Y161417D01*
G01Y1818898D02*
Y1925231D01*
G01Y1818898D02*
Y1925231D01*
G01X-210630Y1929134D02*
G03X-214567Y1925197I0J-3937D01*
G01X-210630Y1929134D02*
G03X-214567Y1925197I0J-3937D01*
G01X-210630Y1929134D02*
X-80709D01*
G01X-210630D02*
X-80709D01*
G01X-175984Y1937008D02*
G03Y1929134I0J-3937D01*
G01X-206693D02*
G03Y1937008I0J3937D01*
G01X-175984D02*
G03Y1929134I0J-3937D01*
G01X-206693D02*
G03Y1937008I0J3937D01*
G01X-175984D02*
X-84638D01*
G01X-214567D02*
X-206693D01*
G01X-84638Y1968504D02*
X-199567D01*
G01X-175984Y1937008D02*
X-84638D01*
G01X-214567D02*
X-206693D01*
G01X-76772Y3937D02*
G03X-72835Y0I3937J0D01*
G01X-76772Y35433D02*
G03X-80709Y39370I-3937J0D01*
G01X-76772Y35433D02*
G03X-80709Y39370I-3937J0D01*
G01X-76772Y3937D02*
G03X-72835Y0I3937J0D01*
G01X-11811D02*
X-72835D01*
G01X-11811D02*
X-72835D01*
G01X-76772Y3937D02*
Y35433D01*
G01Y3937D02*
Y35433D01*
G01X-72835Y0D02*
X-11811D01*
G01X-76772Y3937D02*
G03X-72835Y0I3937J0D01*
G01X-84646Y7874D02*
Y0D01*
G01X-76772Y7874D02*
G03X-84646I-3937J0D01*
G01Y31496D02*
G03X-76772I3937J0D01*
G01X-72835Y0D02*
X-11811D01*
G01X-76772Y3937D02*
G03X-72835Y0I3937J0D01*
G01X-84646Y7874D02*
Y0D01*
G01X-76772Y7874D02*
G03X-84646I-3937J0D01*
G01Y31496D02*
G03X-76772I3937J0D01*
G01X-80709Y1929134D02*
G03X-76772Y1933071I0J3937D01*
G01X-80709Y1929134D02*
G03X-76772Y1933071I0J3937D01*
G01D02*
Y1964567D01*
G01Y1933071D02*
Y1964567D01*
G01X-76763Y1937008D02*
G03X-84638I-3937J0D01*
G01X-72835Y1968504D02*
G03X-76772Y1964567I0J-3937D01*
G01X-72835Y1968504D02*
G03X-76772Y1964567I0J-3937D01*
G01X-72835Y1968504D02*
X-11811D01*
G01X-72835D02*
X-11811D01*
G01X-72835D02*
G03X-76772Y1964567I0J-3937D01*
G01X-11811Y1968504D02*
X-72835D01*
G01X-84638Y1960889D02*
Y1968504D01*
G01Y1960889D02*
G03X-76763I3938J0D01*
G01X-72835Y1968504D02*
G03X-76772Y1964567I0J-3937D01*
G01X-11811Y1968504D02*
X-72835D01*
G01X-84638Y1960889D02*
Y1968504D01*
G01Y1960889D02*
G03X-76763I3938J0D01*
G01X-14018Y-107763D02*
Y-90263D01*
X-8778D01*
X-7031Y-91138D01*
X-5721Y-93180D01*
X-5284Y-95513D01*
X-5721Y-97846D01*
X-6813Y-99596D01*
X-8778Y-100472D01*
X-14018D01*
G01X12652Y-91722D02*
X11342Y-90846D01*
X9814Y-90263D01*
X8067D01*
X6102Y-91138D01*
X4574Y-92596D01*
X3482Y-94347D01*
X2609Y-97263D01*
X2390Y-99888D01*
X2827Y-102513D01*
X3482Y-104263D01*
X4792Y-106013D01*
X6321Y-107180D01*
X7849Y-107763D01*
X9377D01*
X10906Y-107180D01*
X12216Y-106305D01*
X13308Y-105139D01*
G01X27095Y-98430D02*
X27969Y-97555D01*
X28624Y-96097D01*
X29061Y-94054D01*
X28624Y-92305D01*
X27751Y-91138D01*
X26222Y-90263D01*
X20327D01*
Y-107763D01*
X27532D01*
X29061Y-106597D01*
X29934Y-104846D01*
X30371Y-102805D01*
X29934Y-100763D01*
X28624Y-99013D01*
X27095Y-98430D01*
X20327D01*
G01X36299Y-113596D02*
X49399D01*
G01X55327Y-107763D02*
Y-90263D01*
X65371Y-107763D01*
Y-90263D01*
G01X77849Y-107763D02*
X76102Y-107471D01*
X74574Y-106305D01*
X73264Y-104555D01*
X72390Y-102513D01*
X71954Y-100180D01*
Y-97846D01*
X72390Y-95513D01*
X73264Y-93471D01*
X74574Y-91722D01*
X76102Y-90555D01*
X77849Y-90263D01*
X79595Y-90555D01*
X81124Y-91722D01*
X82434Y-93471D01*
X83308Y-95513D01*
X83744Y-97846D01*
Y-100180D01*
X83308Y-102513D01*
X82434Y-104555D01*
X81124Y-106305D01*
X79595Y-107471D01*
X77849Y-107763D01*
G01X-901Y-152763D02*
Y-135263D01*
X-3521Y-138763D01*
G01Y-152763D02*
X1719D01*
G01X12451Y-138180D02*
X13761Y-136430D01*
X15289Y-135555D01*
X17036Y-135263D01*
X19219Y-135846D01*
X20747Y-137305D01*
X21184Y-139054D01*
X20966Y-140805D01*
X20092Y-142263D01*
X15726Y-145180D01*
X13761Y-147221D01*
X12451Y-150139D01*
X12014Y-152763D01*
X21184D01*
G01X36719D02*
Y-135263D01*
X28640Y-147805D01*
X39558D01*
G01X46796Y-149263D02*
X48105Y-151305D01*
X49852Y-152471D01*
X51817Y-152763D01*
X53564Y-152471D01*
X55311Y-151013D01*
X56402Y-149263D01*
X56621Y-147513D01*
X56184Y-145472D01*
X54656Y-144013D01*
X53127Y-143430D01*
X51162D01*
G01X53127D02*
X54437Y-142555D01*
X55529Y-141097D01*
X55966Y-139347D01*
X55529Y-137596D01*
X54437Y-136138D01*
X52472Y-135263D01*
X50507Y-135555D01*
X48542Y-136722D01*
G01X64296Y-149263D02*
X65605Y-151305D01*
X67352Y-152471D01*
X69317Y-152763D01*
X71064Y-152471D01*
X72811Y-151013D01*
X73902Y-149263D01*
X74121Y-147513D01*
X73684Y-145472D01*
X72156Y-144013D01*
X70627Y-143430D01*
X68662D01*
G01X70627D02*
X71937Y-142555D01*
X73029Y-141097D01*
X73466Y-139347D01*
X73029Y-137596D01*
X71937Y-136138D01*
X69972Y-135263D01*
X68007Y-135555D01*
X66042Y-136722D01*
G01X-11811Y0D02*
G03X-7874Y3937I0J3937D01*
G01X-11811Y0D02*
G03X-7874Y3937I0J3937D01*
G01Y43110D02*
Y3937D01*
G01Y43110D02*
Y3937D01*
G01X0D02*
G03X3937Y0I3937J0D01*
G01X0Y3937D02*
G03X3937Y0I3937J0D01*
G01X0Y3937D02*
Y43110D01*
G01Y3937D02*
Y43110D01*
G01X64961Y0D02*
X3937D01*
G01X64961D02*
X3937D01*
G01X0Y3937D02*
G03X3937Y0I3937J0D01*
G01X0Y1964567D02*
Y3937D01*
G01X3937Y0D02*
X64961D01*
G01X-7874Y3937D02*
Y1964567D01*
G01X-11811Y0D02*
G03X-7874Y3937I0J3937D01*
G01X0Y11811D02*
G03X-7874I-3937J0D01*
G01Y42520D02*
G03X0I3937J0D01*
G01Y3937D02*
G03X3937Y0I3937J0D01*
G01X0Y1964567D02*
Y3937D01*
G01X3937Y0D02*
X64961D01*
G01X-7874Y3937D02*
Y1964567D01*
G01X-11811Y0D02*
G03X-7874Y3937I0J3937D01*
G01X0Y11811D02*
G03X-7874I-3937J0D01*
G01Y42520D02*
G03X0I3937J0D01*
G01X-7874Y93110D02*
Y43110D01*
G01Y93110D02*
Y43110D01*
G01X0D02*
Y93110D01*
G01Y43110D02*
Y93110D01*
G01X-7874Y214764D02*
Y93110D01*
G01Y214764D02*
Y93110D01*
G01X0D02*
Y214764D01*
G01Y93110D02*
Y214764D01*
G01X-7874Y226968D02*
Y214764D01*
G01Y226968D02*
Y214764D01*
G01Y342461D02*
Y226968D01*
G01Y342461D02*
Y226968D01*
G01X0Y226969D02*
Y342461D01*
G01Y226969D02*
Y342461D01*
G01Y214764D02*
Y226969D01*
G01Y214764D02*
Y226969D01*
G01Y278740D02*
G03X-7874I-3937J0D01*
G01X0D02*
G03X-7874I-3937J0D01*
G01Y354665D02*
Y342461D01*
G01Y354665D02*
Y342461D01*
G01X0D02*
Y354665D01*
G01Y342461D02*
Y354665D01*
G01X-7874Y309449D02*
G03X0I3937J0D01*
G01X-7874D02*
G03X0I3937J0D01*
G01X-7874Y476339D02*
Y354665D01*
G01Y476339D02*
Y354665D01*
G01X0D02*
Y476339D01*
G01Y354665D02*
Y476339D01*
G01X-7874Y526339D02*
Y476339D01*
G01Y526339D02*
Y476339D01*
G01X0D02*
Y526339D01*
G01Y476339D02*
Y526339D01*
G01X-7874Y736181D02*
Y526339D01*
G01Y736181D02*
Y526339D01*
G01X0D02*
Y736181D01*
G01Y526339D02*
Y736181D01*
G01Y545669D02*
G03X-7874I-3937J0D01*
G01X0D02*
G03X-7874I-3937J0D01*
G01Y576378D02*
G03X0I3937J0D01*
G01X-7874D02*
G03X0I3937J0D01*
G01X-7874Y786181D02*
Y736181D01*
G01Y786181D02*
Y736181D01*
G01X0D02*
Y786181D01*
G01Y736181D02*
Y786181D01*
G01X-7874Y907815D02*
Y786181D01*
G01Y907815D02*
Y786181D01*
G01X0D02*
Y907815D01*
G01Y786181D02*
Y907815D01*
G01X-7874Y862205D02*
G03X0I3937J0D01*
G01Y831496D02*
G03X-7874I-3937J0D01*
G01Y862205D02*
G03X0I3937J0D01*
G01Y831496D02*
G03X-7874I-3937J0D01*
G01Y920020D02*
Y907815D01*
G01Y920020D02*
Y907815D01*
G01X0D02*
Y920020D01*
G01Y907815D02*
Y920020D01*
G01X-7874Y1048484D02*
Y920020D01*
G01Y1048484D02*
Y920020D01*
G01X0D02*
Y1048484D01*
G01Y920020D02*
Y1048484D01*
G01X-7874Y1060689D02*
Y1048484D01*
G01Y1060689D02*
Y1048484D01*
G01Y1182323D02*
Y1060689D01*
G01Y1182323D02*
Y1060689D01*
G01X0D02*
Y1182323D01*
G01Y1060689D02*
Y1182323D01*
G01Y1048484D02*
Y1060689D01*
G01Y1048484D02*
Y1060689D01*
G01Y1106299D02*
G03X-7874I-3937J0D01*
G01X0D02*
G03X-7874I-3937J0D01*
G01Y1137008D02*
G03X0I3937J0D01*
G01X-7874D02*
G03X0I3937J0D01*
G01X-7874Y1232323D02*
Y1182323D01*
G01Y1232323D02*
Y1182323D01*
G01X0D02*
Y1232323D01*
G01Y1182323D02*
Y1232323D01*
G01X-7874Y1442165D02*
Y1232323D01*
G01Y1442165D02*
Y1232323D01*
G01X0D02*
Y1442165D01*
G01Y1232323D02*
Y1442165D01*
G01X-7874Y1422835D02*
G03X0I3937J0D01*
G01Y1392126D02*
G03X-7874I-3937J0D01*
G01Y1422835D02*
G03X0I3937J0D01*
G01Y1392126D02*
G03X-7874I-3937J0D01*
G01Y1492165D02*
Y1442165D01*
G01Y1492165D02*
Y1442165D01*
G01X0D02*
Y1492165D01*
G01Y1442165D02*
Y1492165D01*
G01X-7874Y1613839D02*
Y1492165D01*
G01Y1613839D02*
Y1492165D01*
G01X0D02*
Y1613839D01*
G01Y1492165D02*
Y1613839D01*
G01X-7874Y1626043D02*
Y1613839D01*
G01Y1626043D02*
Y1613839D01*
G01Y1741535D02*
Y1626043D01*
G01Y1741535D02*
Y1626043D01*
G01X0D02*
Y1741535D01*
G01Y1626043D02*
Y1741535D01*
G01Y1613839D02*
Y1626043D01*
G01Y1613839D02*
Y1626043D01*
G01Y1659055D02*
G03X-7874I-3937J0D01*
G01X0D02*
G03X-7874I-3937J0D01*
G01Y1689764D02*
G03X0I3937J0D01*
G01X-7874D02*
G03X0I3937J0D01*
G01X-7874Y1753740D02*
Y1741535D01*
G01Y1753740D02*
Y1741535D01*
G01Y1875394D02*
Y1753740D01*
G01Y1875394D02*
Y1753740D01*
G01X0D02*
Y1875394D01*
G01Y1753740D02*
Y1875394D01*
G01Y1741535D02*
Y1753740D01*
G01Y1741535D02*
Y1753740D01*
G01X-7874Y1925394D02*
Y1875394D01*
G01Y1925394D02*
Y1875394D01*
G01X0D02*
Y1925394D01*
G01Y1875394D02*
Y1925394D01*
G01X-7874Y1964567D02*
Y1925394D01*
G01Y1964567D02*
Y1925394D01*
G01X0D02*
Y1964567D01*
G01Y1925394D02*
Y1964567D01*
G01Y1925984D02*
G03X-7874I-3937J0D01*
G01X0D02*
G03X-7874I-3937J0D01*
G01Y1964567D02*
G03X-11811Y1968504I-3937J0D01*
G01X-7874Y1964567D02*
G03X-11811Y1968504I-3937J0D01*
G01X3937D02*
G03X0Y1964567I0J-3937D01*
G01X3937Y1968504D02*
G03X0Y1964567I0J-3937D01*
G01X3937Y1968504D02*
X64961D01*
G01X3937D02*
X64961D01*
G01X3937D02*
G03X0Y1964567I0J-3937D01*
G01X64961Y1968504D02*
X3937D01*
G01X-7874Y1964567D02*
G03X-11811Y1968504I-3937J0D01*
G01X-7874Y1956693D02*
G03X0I3937J0D01*
G01X3937Y1968504D02*
G03X0Y1964567I0J-3937D01*
G01X64961Y1968504D02*
X3937D01*
G01X-7874Y1964567D02*
G03X-11811Y1968504I-3937J0D01*
G01X-7874Y1956693D02*
G03X0I3937J0D01*
G01X168110Y31496D02*
X76763D01*
G01X72835Y39370D02*
G03X68898Y35433I0J-3937D01*
G01X72835Y39370D02*
G03X68898Y35433I0J-3937D01*
G01X64961Y0D02*
G03X68898Y3937I0J3937D01*
G01X64961Y0D02*
G03X68898Y3937I0J3937D01*
G01Y35433D02*
Y3937D01*
G01Y35433D02*
Y3937D01*
G01X202756Y39370D02*
X72835D01*
G01X202756D02*
X72835D01*
G01D02*
X202756D01*
G01X72835D02*
G03X68898Y35433I0J-3937D01*
G01Y3937D02*
Y35485D01*
G01X64961Y0D02*
G03X68898Y3937I0J3937D01*
G01X76763D02*
G03X80700Y0I3937J0D01*
G01X76763Y7615D02*
Y3937D01*
G01X80700Y0D02*
X340551D01*
G01X168110Y31496D02*
X76763D01*
G01Y7615D02*
G03X68889I-3937J0D01*
G01Y31496D02*
G03X76763I3937J0D01*
G01X72835Y39370D02*
X202756D01*
G01X72835D02*
G03X68898Y35433I0J-3937D01*
G01Y3937D02*
Y35485D01*
G01X64961Y0D02*
G03X68898Y3937I0J3937D01*
G01X76763D02*
G03X80700Y0I3937J0D01*
G01X76763Y7615D02*
Y3937D01*
G01X80700Y0D02*
X340551D01*
G01X168110Y31496D02*
X76763D01*
G01Y7615D02*
G03X68889I-3937J0D01*
G01Y31496D02*
G03X76763I3937J0D01*
G01X68898Y1933071D02*
G03X72835Y1929134I3937J0D01*
G01X68898Y1933071D02*
G03X72835Y1929134I3937J0D01*
G01D02*
X202756D01*
G01X72835D02*
X202756D01*
G01X68898Y1964567D02*
Y1933071D01*
G01Y1964567D02*
Y1933071D01*
G01D02*
Y1964567D01*
G01Y1933071D02*
G03X72835Y1929134I3937J0D01*
G01X202756D02*
X72835D01*
G01X68898Y1933071D02*
Y1964567D01*
G01Y1933071D02*
G03X72835Y1929134I3937J0D01*
G01X202756D02*
X72835D01*
G01X68898Y1964567D02*
G03X64961Y1968504I-3937J0D01*
G01X68898Y1964567D02*
G03X64961Y1968504I-3937J0D01*
G01X68898Y1964567D02*
G03X64961Y1968504I-3937J0D01*
G01X109377D02*
X80709D01*
G01D02*
G03X76772Y1964567I0J-3937D01*
G01Y1960630D02*
Y1964567D01*
G01X168110Y1937008D02*
X76772D01*
G01X68898Y1960630D02*
G03X76772I3937J0D01*
G01Y1937008D02*
G03X68898I-3937J0D01*
G01Y1964567D02*
G03X64961Y1968504I-3937J0D01*
G01X109377D02*
X80709D01*
G01D02*
G03X76772Y1964567I0J-3937D01*
G01Y1960630D02*
Y1964567D01*
G01X168110Y1937008D02*
X76772D01*
G01X68898Y1960630D02*
G03X76772I3937J0D01*
G01Y1937008D02*
G03X68898I-3937J0D01*
G01X128690Y-90263D02*
X134149Y-107763D01*
X139608Y-90263D01*
G01X156016Y-107763D02*
X147282D01*
Y-90263D01*
X156016D01*
G01X152522Y-98721D02*
X147282D01*
G01X164782Y-107763D02*
Y-90263D01*
X170241D01*
X171987Y-91138D01*
X173079Y-92305D01*
X173516Y-94638D01*
X173079Y-96972D01*
X171769Y-98430D01*
X170241Y-99305D01*
X164782D01*
G01X170241D02*
X173516Y-107763D01*
G01X186649Y-108346D02*
X186212Y-108055D01*
Y-107471D01*
X186649Y-107180D01*
X187086Y-107471D01*
Y-108055D01*
X186649Y-108346D01*
G01X118011Y1968504D02*
X142520D01*
G01X109377D02*
X110137D01*
G01D02*
G03X118011I3937J0D01*
G01X110137D02*
G03X118011I3937J0D01*
G01X147501Y-138180D02*
X148811Y-136430D01*
X150339Y-135555D01*
X152086Y-135263D01*
X154269Y-135846D01*
X155797Y-137305D01*
X156234Y-139054D01*
X156016Y-140805D01*
X155142Y-142263D01*
X150776Y-145180D01*
X148811Y-147221D01*
X147501Y-150139D01*
X147064Y-152763D01*
X156234D01*
G01X163690D02*
X169149Y-135263D01*
X174608Y-152763D01*
G01X172642Y-146638D02*
X165655D01*
G01X168110Y31496D02*
G03Y39370I0J3937D01*
G01Y31496D02*
G03Y39370I0J3937D01*
G01Y1929134D02*
G03Y1937008I0J3937D01*
G01Y1929134D02*
G03Y1937008I0J3937D01*
G01X340559Y1968504D02*
X142520D01*
G01X340559D02*
X142520D01*
G01X202756Y39370D02*
G03X206693Y43307I0J3937D01*
G01X202756Y39370D02*
G03X206693Y43307I0J3937D01*
G01X202756Y39370D02*
G03X206693Y43307I0J3937D01*
G01X218504Y39370D02*
X348425D01*
G01X214567Y43307D02*
G03X218504Y39370I3937J0D01*
G01X222441Y31496D02*
X198819D01*
G01X222441D02*
G03Y39370I0J3937D01*
G01X198819D02*
G03Y31496I0J-3937D01*
G01X202756Y39370D02*
G03X206693Y43307I0J3937D01*
G01X218504Y39370D02*
X348425D01*
G01X214567Y43307D02*
G03X218504Y39370I3937J0D01*
G01X222441Y31496D02*
X198819D01*
G01X222441D02*
G03Y39370I0J3937D01*
G01X198819D02*
G03Y31496I0J-3937D01*
G01X214567Y161417D02*
Y43307D01*
G01X206693Y1925197D02*
Y43307D01*
G01Y1925197D02*
Y43307D01*
G01Y161417D02*
Y1807087D01*
G01X214567D02*
Y161417D01*
G01Y169291D02*
G03X206693I-3937J0D01*
G01Y161417D02*
Y1807087D01*
G01X214567D02*
Y161417D01*
G01Y169291D02*
G03X206693I-3937J0D01*
G01Y200000D02*
G03X214567I3937J0D01*
G01X206693D02*
G03X214567I3937J0D01*
G01Y436220D02*
G03X206693I-3937J0D01*
G01X214567D02*
G03X206693I-3937J0D01*
G01Y466929D02*
G03X214567I3937J0D01*
G01X206693D02*
G03X214567I3937J0D01*
G01Y703149D02*
G03X206693I-3937J0D01*
G01X214567D02*
G03X206693I-3937J0D01*
G01Y733858D02*
G03X214567I3937J0D01*
G01X206693D02*
G03X214567I3937J0D01*
G01Y970867D02*
G03X206693I-3937J0D01*
G01Y997637D02*
G03X214567I3937J0D01*
G01Y970867D02*
G03X206693I-3937J0D01*
G01Y997637D02*
G03X214567I3937J0D01*
G01X206693Y1265355D02*
G03X214567I3937J0D01*
G01Y1234646D02*
G03X206693I-3937J0D01*
G01Y1265355D02*
G03X214567I3937J0D01*
G01Y1234646D02*
G03X206693I-3937J0D01*
G01X214567Y1501575D02*
G03X206693I-3937J0D01*
G01X214567D02*
G03X206693I-3937J0D01*
G01Y1532284D02*
G03X214567I3937J0D01*
G01X206693D02*
G03X214567I3937J0D01*
G01Y1768504D02*
G03X206693I-3937J0D01*
G01X214567D02*
G03X206693I-3937J0D01*
G01X214567Y1807087D02*
Y1925197D01*
G01X206693Y1799213D02*
G03X214567I3937J0D01*
G01X206693D02*
G03X214567I3937J0D01*
G01X206693Y1925197D02*
G03X202756Y1929134I-3937J0D01*
G01X206693Y1925197D02*
G03X202756Y1929134I-3937J0D01*
G01X206693Y1925197D02*
G03X202756Y1929134I-3937J0D01*
G01X218504D02*
G03X214567Y1925197I0J-3937D01*
G01X348425Y1929134D02*
X218504D01*
G01X198819Y1937008D02*
G03Y1929134I0J-3937D01*
G01X222441D02*
G03Y1937008I0J3937D01*
G01X206693Y1925197D02*
G03X202756Y1929134I-3937J0D01*
G01X218504D02*
G03X214567Y1925197I0J-3937D01*
G01X348425Y1929134D02*
X218504D01*
G01X198819Y1937008D02*
G03Y1929134I0J-3937D01*
G01X222441D02*
G03Y1937008I0J3937D01*
G01X198819D02*
X222441D01*
G01X198819D02*
X222441D01*
G01X253482Y-90263D02*
Y-107763D01*
X262216D01*
G01X279279D02*
Y-96097D01*
G01Y-98138D02*
X278406Y-96972D01*
X277095Y-96388D01*
X275567Y-96097D01*
X274039Y-96680D01*
X272729Y-97846D01*
X271855Y-99596D01*
X271419Y-101930D01*
X271855Y-104263D01*
X272729Y-106013D01*
X274039Y-107180D01*
X275567Y-107763D01*
X277095Y-107471D01*
X278406Y-106597D01*
X279279Y-105430D01*
G01X288264Y-113013D02*
X289574Y-113596D01*
X291321Y-113013D01*
X292412Y-111847D01*
X293286Y-110388D01*
X294595Y-105722D01*
X297434Y-96097D01*
G01X290447D02*
X294595Y-105722D01*
G01X307074Y-99888D02*
X314061D01*
X313406Y-97846D01*
X312314Y-96680D01*
X310786Y-96097D01*
X309257Y-96388D01*
X307947Y-97263D01*
X307074Y-99305D01*
X306637Y-101055D01*
Y-102805D01*
X307074Y-104555D01*
X308166Y-106305D01*
X309476Y-107471D01*
X311004Y-107763D01*
X312532Y-107180D01*
X314061Y-105430D01*
G01X324792Y-107763D02*
Y-96097D01*
G01Y-98430D02*
X325884Y-97263D01*
X326976Y-96388D01*
X328504Y-96097D01*
X329595Y-96388D01*
X330906Y-97263D01*
G01X342074Y-105722D02*
X343166Y-106888D01*
X344694Y-107763D01*
X346004D01*
X347314Y-107180D01*
X348187Y-106305D01*
X348624Y-105139D01*
X348406Y-103388D01*
X347532Y-102513D01*
X343602Y-100763D01*
X342729Y-98721D01*
X343166Y-97263D01*
X344039Y-96388D01*
X345349Y-96097D01*
X346659Y-96388D01*
X347969Y-97263D01*
G01X259159Y-144013D02*
X263526D01*
Y-149263D01*
X262216Y-151013D01*
X260687Y-152180D01*
X258504Y-152763D01*
X256321Y-152180D01*
X254792Y-151013D01*
X253482Y-149263D01*
X252609Y-147221D01*
X252172Y-144888D01*
Y-142846D01*
X252609Y-141097D01*
X253482Y-139054D01*
X254792Y-137305D01*
X256102Y-136138D01*
X257849Y-135263D01*
X259377D01*
X261124Y-135846D01*
X262434Y-137013D01*
G01X275349Y-152763D02*
X273602Y-152471D01*
X272074Y-151305D01*
X270764Y-149555D01*
X269890Y-147513D01*
X269454Y-145180D01*
Y-142846D01*
X269890Y-140513D01*
X270764Y-138471D01*
X272074Y-136722D01*
X273602Y-135555D01*
X275349Y-135263D01*
X277095Y-135555D01*
X278624Y-136722D01*
X279934Y-138471D01*
X280808Y-140513D01*
X281244Y-142846D01*
Y-145180D01*
X280808Y-147513D01*
X279934Y-149555D01*
X278624Y-151305D01*
X277095Y-152471D01*
X275349Y-152763D01*
G01X288482Y-135263D02*
Y-152763D01*
X297216D01*
G01X305546D02*
Y-135263D01*
X309912D01*
X311659Y-136138D01*
X312969Y-137305D01*
X314061Y-139054D01*
X314934Y-141097D01*
X315152Y-144013D01*
X314934Y-146930D01*
X314061Y-148972D01*
X312969Y-150722D01*
X311659Y-151888D01*
X309912Y-152763D01*
X305546D01*
G01X321299Y-158596D02*
X334399D01*
G01X345349Y-135263D02*
Y-152763D01*
G01X340327Y-135263D02*
X350371D01*
G01X253150Y31496D02*
X344488D01*
G01X253150Y39370D02*
G03Y31496I0J-3937D01*
G01D02*
X344488D01*
G01X253150Y39370D02*
G03Y31496I0J-3937D01*
G01Y1937008D02*
G03Y1929134I0J-3937D01*
G01Y1937008D02*
G03Y1929134I0J-3937D01*
G01Y1937008D02*
X344496D01*
G01X253150D02*
X344496D01*
G01X340551Y0D02*
G03X344488Y3937I0J3937D01*
G01X340551Y0D02*
G03X344488Y3937I0J3937D01*
G01X344496Y1964567D02*
G03X340559Y1968504I-3937J0D01*
G01X344496Y1964567D02*
G03X340559Y1968504I-3937J0D01*
G01X356299Y0D02*
X417323D01*
G01X352362Y3937D02*
G03X356299Y0I3937J0D01*
G01X352362Y35433D02*
Y3937D01*
G01Y35433D02*
G03X348425Y39370I-3937J0D01*
G01X344488Y7874D02*
Y3937D01*
G01X352362Y7874D02*
G03X344488I-3937J0D01*
G01Y31496D02*
G03X352362I3937J0D01*
G01X356299Y0D02*
X417323D01*
G01X352362Y3937D02*
G03X356299Y0I3937J0D01*
G01X352362Y35433D02*
Y3937D01*
G01Y35433D02*
G03X348425Y39370I-3937J0D01*
G01X344488Y7874D02*
Y3937D01*
G01X352362Y7874D02*
G03X344488I-3937J0D01*
G01Y31496D02*
G03X352362I3937J0D01*
G01X348425Y1929134D02*
G03X352362Y1933071I0J3937D01*
G01Y1964567D02*
Y1933071D01*
G01X348425Y1929134D02*
G03X352362Y1933071I0J3937D01*
G01Y1964567D02*
Y1933071D01*
G01X356299Y1968504D02*
G03X352362Y1964567I0J-3937D01*
G01X417323Y1968504D02*
X356299D01*
G01X344496Y1960889D02*
Y1964567D01*
G01Y1960889D02*
G03X352370I3937J0D01*
G01Y1937008D02*
G03X344496I-3937J0D01*
G01X356299Y1968504D02*
G03X352362Y1964567I0J-3937D01*
G01X417323Y1968504D02*
X356299D01*
G01X344496Y1960889D02*
Y1964567D01*
G01Y1960889D02*
G03X352370I3937J0D01*
G01Y1937008D02*
G03X344496I-3937J0D01*
G01X404346Y-107763D02*
Y-90263D01*
X408712D01*
X410459Y-91138D01*
X411769Y-92305D01*
X412861Y-94054D01*
X413734Y-96097D01*
X413952Y-99013D01*
X413734Y-101930D01*
X412861Y-103972D01*
X411769Y-105722D01*
X410459Y-106888D01*
X408712Y-107763D01*
X404346D01*
G01X423374Y-99888D02*
X430361D01*
X429706Y-97846D01*
X428614Y-96680D01*
X427086Y-96097D01*
X425557Y-96388D01*
X424247Y-97263D01*
X423374Y-99305D01*
X422937Y-101055D01*
Y-102805D01*
X423374Y-104555D01*
X424466Y-106305D01*
X425776Y-107471D01*
X427304Y-107763D01*
X428832Y-107180D01*
X430361Y-105430D01*
G01X440874Y-105722D02*
X441966Y-106888D01*
X443494Y-107763D01*
X444804D01*
X446114Y-107180D01*
X446987Y-106305D01*
X447424Y-105139D01*
X447206Y-103388D01*
X446332Y-102513D01*
X442402Y-100763D01*
X441529Y-98721D01*
X441966Y-97263D01*
X442839Y-96388D01*
X444149Y-96097D01*
X445459Y-96388D01*
X446769Y-97263D01*
G01X461649Y-96097D02*
Y-107763D01*
G01Y-91430D02*
X461212Y-91138D01*
Y-90555D01*
X461649Y-90263D01*
X462086Y-90555D01*
Y-91138D01*
X461649Y-91430D01*
G01X476092Y-112138D02*
X477621Y-113305D01*
X479367Y-113596D01*
X480895Y-113305D01*
X482206Y-111847D01*
X483079Y-109805D01*
Y-96097D01*
G01Y-98430D02*
X482206Y-97263D01*
X480895Y-96388D01*
X479367Y-96097D01*
X477621Y-96680D01*
X476529Y-97846D01*
X475655Y-99888D01*
X475219Y-101930D01*
X475437Y-103680D01*
X476311Y-105722D01*
X477621Y-107180D01*
X479367Y-107763D01*
X480677Y-107471D01*
X482206Y-106305D01*
X483079Y-105139D01*
G01X492937Y-107763D02*
Y-96097D01*
G01Y-99013D02*
X493811Y-97555D01*
X495121Y-96388D01*
X496867Y-96097D01*
X498395Y-96388D01*
X499706Y-97555D01*
X500361Y-99596D01*
Y-107763D01*
G01X510874Y-99888D02*
X517861D01*
X517206Y-97846D01*
X516114Y-96680D01*
X514586Y-96097D01*
X513057Y-96388D01*
X511747Y-97263D01*
X510874Y-99305D01*
X510437Y-101055D01*
Y-102805D01*
X510874Y-104555D01*
X511966Y-106305D01*
X513276Y-107471D01*
X514804Y-107763D01*
X516332Y-107180D01*
X517861Y-105430D01*
G01X528592Y-107763D02*
Y-96097D01*
G01Y-98430D02*
X529684Y-97263D01*
X530776Y-96388D01*
X532304Y-96097D01*
X533395Y-96388D01*
X534706Y-97263D01*
G01X429722Y-152763D02*
Y-135263D01*
X435399Y-149846D01*
X441076Y-135263D01*
Y-152763D01*
G01X452899D02*
X451152Y-152471D01*
X449624Y-151305D01*
X448314Y-149555D01*
X447440Y-147513D01*
X447004Y-145180D01*
Y-142846D01*
X447440Y-140513D01*
X448314Y-138471D01*
X449624Y-136722D01*
X451152Y-135555D01*
X452899Y-135263D01*
X454645Y-135555D01*
X456174Y-136722D01*
X457484Y-138471D01*
X458358Y-140513D01*
X458794Y-142846D01*
Y-145180D01*
X458358Y-147513D01*
X457484Y-149555D01*
X456174Y-151305D01*
X454645Y-152471D01*
X452899Y-152763D01*
G01X465814Y-150430D02*
X467561Y-151888D01*
X469526Y-152763D01*
X471272D01*
X473019Y-151888D01*
X474329Y-150430D01*
X474984Y-148388D01*
X474547Y-146347D01*
X473456Y-144596D01*
X471491Y-143430D01*
X468871Y-142846D01*
X467342Y-141680D01*
X466687Y-139638D01*
X467124Y-137596D01*
X468216Y-136138D01*
X469744Y-135263D01*
X471272D01*
X472801Y-135846D01*
X474111Y-137305D01*
G01X483314Y-150430D02*
X485061Y-151888D01*
X487026Y-152763D01*
X488772D01*
X490519Y-151888D01*
X491829Y-150430D01*
X492484Y-148388D01*
X492047Y-146347D01*
X490956Y-144596D01*
X488991Y-143430D01*
X486371Y-142846D01*
X484842Y-141680D01*
X484187Y-139638D01*
X484624Y-137596D01*
X485716Y-136138D01*
X487244Y-135263D01*
X488772D01*
X490301Y-135846D01*
X491611Y-137305D01*
G01X509766Y-152763D02*
X501032D01*
Y-135263D01*
X509766D01*
G01X506272Y-143721D02*
X501032D01*
G01X429134Y3937D02*
G03X433071Y0I3937J0D01*
G01X429134Y1964567D02*
Y3937D01*
G01X433071Y0D02*
X494095D01*
G01X421260Y3937D02*
Y1964567D01*
G01X417323Y0D02*
G03X421260Y3937I0J3937D01*
G01X429134Y11811D02*
G03X421260I-3937J0D01*
G01Y42520D02*
G03X429134I3937J0D01*
G01Y3937D02*
G03X433071Y0I3937J0D01*
G01X429134Y1964567D02*
Y3937D01*
G01X433071Y0D02*
X494095D01*
G01X421260Y3937D02*
Y1964567D01*
G01X417323Y0D02*
G03X421260Y3937I0J3937D01*
G01X429134Y11811D02*
G03X421260I-3937J0D01*
G01Y42520D02*
G03X429134I3937J0D01*
G01Y278740D02*
G03X421260I-3937J0D01*
G01X429134D02*
G03X421260I-3937J0D01*
G01Y309449D02*
G03X429134I3937J0D01*
G01X421260D02*
G03X429134I3937J0D01*
G01Y545669D02*
G03X421260I-3937J0D01*
G01X429134D02*
G03X421260I-3937J0D01*
G01Y576378D02*
G03X429134I3937J0D01*
G01X421260D02*
G03X429134I3937J0D01*
G01X421260Y862205D02*
G03X429134I3937J0D01*
G01Y831496D02*
G03X421260I-3937J0D01*
G01Y862205D02*
G03X429134I3937J0D01*
G01Y831496D02*
G03X421260I-3937J0D01*
G01X429134Y1106299D02*
G03X421260I-3937J0D01*
G01X429134D02*
G03X421260I-3937J0D01*
G01Y1137008D02*
G03X429134I3937J0D01*
G01X421260D02*
G03X429134I3937J0D01*
G01X421260Y1422835D02*
G03X429134I3937J0D01*
G01Y1392126D02*
G03X421260I-3937J0D01*
G01Y1422835D02*
G03X429134I3937J0D01*
G01Y1392126D02*
G03X421260I-3937J0D01*
G01X429134Y1659055D02*
G03X421260I-3937J0D01*
G01X429134D02*
G03X421260I-3937J0D01*
G01Y1689764D02*
G03X429134I3937J0D01*
G01X421260D02*
G03X429134I3937J0D01*
G01Y1925984D02*
G03X421260I-3937J0D01*
G01X429134D02*
G03X421260I-3937J0D01*
G01X433071Y1968504D02*
G03X429134Y1964567I0J-3937D01*
G01X494095Y1968504D02*
X433071D01*
G01X421260Y1964567D02*
G03X417323Y1968504I-3937J0D01*
G01X421260Y1956693D02*
G03X429134I3937J0D01*
G01X433071Y1968504D02*
G03X429134Y1964567I0J-3937D01*
G01X494095Y1968504D02*
X433071D01*
G01X421260Y1964567D02*
G03X417323Y1968504I-3937J0D01*
G01X421260Y1956693D02*
G03X429134I3937J0D01*
G01X433071Y1968504D02*
G03X429134Y1964567I0J-3937D01*
G01X421260D02*
G03X417323Y1968504I-3937J0D01*
G01X494095Y0D02*
G03X498032Y3937I0J3937D01*
G01X494095Y0D02*
G03X498032Y3937I0J3937D01*
G01Y1964567D02*
G03X494095Y1968504I-3937J0D01*
G01X498032Y1964567D02*
G03X494095Y1968504I-3937J0D01*
G01X501969Y39370D02*
X631890D01*
G01X501969D02*
G03X498032Y35433I0J-3937D01*
G01Y3937D02*
Y35433D01*
G01X505897Y0D02*
X648386D01*
G01X505897Y7615D02*
Y0D01*
G01X597244Y31496D02*
X505897D01*
G01Y7615D02*
G03X498023I-3937J0D01*
G01Y31496D02*
G03X505897I3937J0D01*
G01X501969Y39370D02*
X631890D01*
G01X501969D02*
G03X498032Y35433I0J-3937D01*
G01Y3937D02*
Y35433D01*
G01X505897Y0D02*
X620827D01*
G01X505897Y7615D02*
Y0D01*
G01X597244Y31496D02*
X505897D01*
G01Y7615D02*
G03X498023I-3937J0D01*
G01Y31496D02*
G03X505897I3937J0D01*
G01X498032Y1933071D02*
Y1960630D01*
G01Y1933071D02*
G03X501969Y1929134I3937J0D01*
G01X631890D02*
X501969D01*
G01X498032Y1933071D02*
Y1964567D01*
G01Y1933071D02*
G03X501969Y1929134I3937J0D01*
G01X631890D02*
X501969D01*
G01X505906Y1960630D02*
Y1968504D01*
G01D02*
X648386D01*
G01X597244Y1937008D02*
X505906D01*
G01X498032Y1960630D02*
G03X505906I3937J0D01*
G01Y1937008D02*
G03X498032I-3937J0D01*
G01X505906Y1960630D02*
Y1968504D01*
G01D02*
X620827D01*
G01X597244Y1937008D02*
X505906D01*
G01X498032Y1960630D02*
G03X505906I3937J0D01*
G01Y1937008D02*
G03X498032I-3937J0D01*
G01X575349Y-152763D02*
Y-135263D01*
X572729Y-138763D01*
G01Y-152763D02*
X577969D01*
G01X588701Y-138180D02*
X590011Y-136430D01*
X591539Y-135555D01*
X593286Y-135263D01*
X595469Y-135846D01*
X596997Y-137305D01*
X597434Y-139054D01*
X597216Y-140805D01*
X596342Y-142263D01*
X591976Y-145180D01*
X590011Y-147221D01*
X588701Y-150139D01*
X588264Y-152763D01*
X597434D01*
G01X606419Y-153346D02*
X614279Y-135263D01*
G01X627849Y-152763D02*
Y-135263D01*
X625229Y-138763D01*
G01Y-152763D02*
X630469D01*
G01X645349D02*
Y-135263D01*
X642729Y-138763D01*
G01Y-152763D02*
X647969D01*
G01X658919Y-153346D02*
X666779Y-135263D01*
G01X676201Y-138180D02*
X677511Y-136430D01*
X679039Y-135555D01*
X680786Y-135263D01*
X682969Y-135846D01*
X684497Y-137305D01*
X684934Y-139054D01*
X684716Y-140805D01*
X683842Y-142263D01*
X679476Y-145180D01*
X677511Y-147221D01*
X676201Y-150139D01*
X675764Y-152763D01*
X684934D01*
G01X697849Y-135263D02*
X696102Y-135846D01*
X694792Y-137305D01*
X693919Y-139054D01*
X693264Y-141388D01*
X693046Y-144013D01*
X693264Y-146638D01*
X693919Y-148972D01*
X694792Y-150722D01*
X696102Y-152180D01*
X697849Y-152763D01*
X699595Y-152180D01*
X700906Y-150722D01*
X701779Y-148972D01*
X702434Y-146638D01*
X702652Y-144013D01*
X702434Y-141388D01*
X701779Y-139054D01*
X700906Y-137305D01*
X699595Y-135846D01*
X697849Y-135263D01*
G01X715349Y-152763D02*
Y-135263D01*
X712729Y-138763D01*
G01Y-152763D02*
X717969D01*
G01X728046Y-150139D02*
X729355Y-151597D01*
X730884Y-152471D01*
X732849Y-152763D01*
X734814Y-152180D01*
X736342Y-151013D01*
X737434Y-148972D01*
X737652Y-146638D01*
X737216Y-144305D01*
X736124Y-142846D01*
X734595Y-141680D01*
X733067Y-141388D01*
X731539Y-141680D01*
X729574Y-142846D01*
X730229Y-135263D01*
X736124D01*
G01X623046Y-107763D02*
Y-90263D01*
X627412D01*
X629159Y-91138D01*
X630469Y-92305D01*
X631561Y-94054D01*
X632434Y-96097D01*
X632652Y-99013D01*
X632434Y-101930D01*
X631561Y-103972D01*
X630469Y-105722D01*
X629159Y-106888D01*
X627412Y-107763D01*
X623046D01*
G01X649279D02*
Y-96097D01*
G01Y-98138D02*
X648406Y-96972D01*
X647095Y-96388D01*
X645567Y-96097D01*
X644039Y-96680D01*
X642729Y-97846D01*
X641855Y-99596D01*
X641419Y-101930D01*
X641855Y-104263D01*
X642729Y-106013D01*
X644039Y-107180D01*
X645567Y-107763D01*
X647095Y-107471D01*
X648406Y-106597D01*
X649279Y-105430D01*
G01X662849Y-90263D02*
Y-107763D01*
G01X659792Y-96097D02*
X665906D01*
G01X677074Y-99888D02*
X684061D01*
X683406Y-97846D01*
X682314Y-96680D01*
X680786Y-96097D01*
X679257Y-96388D01*
X677947Y-97263D01*
X677074Y-99305D01*
X676637Y-101055D01*
Y-102805D01*
X677074Y-104555D01*
X678166Y-106305D01*
X679476Y-107471D01*
X681004Y-107763D01*
X682532Y-107180D01*
X684061Y-105430D01*
G01X643701Y169256D02*
Y39370D01*
G01X635827Y31496D02*
G03X643701Y39370I0J7874D01*
G01X650689Y19685D02*
G03I-6988J0D01*
G01X631890Y39370D02*
G03X635827Y43307I0J3937D01*
G01Y31496D02*
X627953D01*
G01X597244D02*
G03Y39370I0J3937D01*
G01X627953D02*
G03Y31496I0J-3937D01*
G01X650689Y19685D02*
G03I-6988J0D01*
G01X631890Y39370D02*
G03X635827Y43307I0J3937D01*
G01Y31496D02*
X627953D01*
G01X597244D02*
G03Y39370I0J3937D01*
G01X627953D02*
G03Y31496I0J-3937D01*
G01X635827Y161417D02*
Y43307D01*
G01X643701Y169256D02*
G03X635827I-3937J0D01*
G01X643701D02*
G03X635827I-3937J0D01*
G01Y161417D02*
Y1807087D01*
G01Y161417D02*
Y1807087D01*
G01X643701Y436186D02*
Y199965D01*
G01X635827D02*
G03X643701I3937J0D01*
G01X635827D02*
G03X643701I3937J0D01*
G01Y436186D02*
G03X635827I-3937J0D01*
G01X643701D02*
G03X635827I-3937J0D01*
G01X643701Y703115D02*
Y466894D01*
G01X635827D02*
G03X643701I3937J0D01*
G01X635827D02*
G03X643701I3937J0D01*
G01Y703115D02*
G03X635827I-3937J0D01*
G01X643701D02*
G03X635827I-3937J0D01*
G01X643701Y970832D02*
Y733823D01*
G01X635827D02*
G03X643701I3937J0D01*
G01X635827D02*
G03X643701I3937J0D01*
G01Y1234611D02*
Y997603D01*
G01X635827D02*
G03X643701I3937J0D01*
G01Y970832D02*
G03X635827I-3937J0D01*
G01Y997603D02*
G03X643701I3937J0D01*
G01Y970832D02*
G03X635827I-3937J0D01*
G01X643701Y1501541D02*
Y1265320D01*
G01X635827D02*
G03X643701I3937J0D01*
G01Y1234611D02*
G03X635827I-3937J0D01*
G01Y1265320D02*
G03X643701I3937J0D01*
G01Y1234611D02*
G03X635827I-3937J0D01*
G01X643701Y1501541D02*
G03X635827I-3937J0D01*
G01X643701D02*
G03X635827I-3937J0D01*
G01X643701Y1768470D02*
Y1532249D01*
G01X635827D02*
G03X643701I3937J0D01*
G01X635827D02*
G03X643701I3937J0D01*
G01Y1768470D02*
G03X635827I-3937J0D01*
G01X643701D02*
G03X635827I-3937J0D01*
G01Y1799178D02*
G03X643701I3937J0D01*
G01X635827D02*
G03X643701I3937J0D01*
G01Y1929134D02*
Y1799178D01*
G01X635827Y1818898D02*
Y1807087D01*
G01Y1818898D02*
Y1925197D01*
G01Y1818898D02*
Y1925197D01*
G01X643701Y1929134D02*
G03X635827Y1937008I-7874J0D01*
G01Y1925197D02*
G03X631890Y1929134I-3937J0D01*
G01X627953Y1937008D02*
G03Y1929134I0J-3937D01*
G01X597244D02*
G03Y1937008I0J3937D01*
G01X635827Y1925197D02*
G03X631890Y1929134I-3937J0D01*
G01X627953Y1937008D02*
G03Y1929134I0J-3937D01*
G01X597244D02*
G03Y1937008I0J3937D01*
G01X650689Y1948819D02*
G03I-6988J0D01*
G01X627953Y1937008D02*
X635827D01*
G01X650689Y1948819D02*
G03I-6988J0D01*
G01X627953Y1937008D02*
X635827D01*
G01X650689Y1948819D02*
G03I-6988J0D01*
G01X648386Y0D02*
G03X663386Y15000I0J15000D01*
G01Y1953504D02*
Y15000D01*
G01Y1953504D02*
G03X648386Y1968504I-15000J0D01*
M02*
